#ISCELL
  mstr_symbols cad_note *
  *
#ISCELL
  mstr_symbols design_note *
  *
#ISCELL
  mstr_symbols intel_corp_bpage *
  *
#CELL
  dev_discrete cap_a *
  page131_i1
#CELL
  dev_discrete cap_a *
  page131_i10
#CELL
  dev_discrete cap_a *
  page131_i11
#CELL
  dev_discrete cap_a *
  page131_i12
#ISCELL
  mstr_symbols gnd *
  page131_i13
#CELL
  dev_discrete cap_a *
  page131_i14
#CELL
  dev_discrete cap_a *
  page131_i15
#CELL
  dev_discrete cap_a *
  page131_i16
#ISCELL
  mstr_symbols p1v05_pch_stby *
  page131_i17
#CELL
  dev_discrete cap_a *
  page131_i18
#ISCELL
  mstr_symbols p1v05_pch_stby *
  page131_i19
#CELL
  dev_discrete cap_a *
  page131_i2
#CELL
  dev_discrete cap_a *
  page131_i20
#ISCELL
  mstr_symbols gnd *
  page131_i21
#CELL
  mstr_discrete cap *
  page131_i22
#ISCELL
  mstr_symbols p1v05_pch_stby *
  page131_i23
#CELL
  mstr_discrete cap *
  page131_i24
#ISCELL
  mstr_symbols gnd *
  page131_i25
#ISCELL
  mstr_symbols p1v05_pch_stby *
  page131_i26
#CELL
  dev_discrete cap_a *
  page131_i27
#CELL
  dev_discrete cap_a *
  page131_i28
#CELL
  dev_discrete cap_a *
  page131_i29
#CELL
  dev_discrete cap_a *
  page131_i3
#ISCELL
  mstr_symbols gnd *
  page131_i30
#CELL
  dev_discrete cap_a *
  page131_i31
#CELL
  dev_discrete cap_a *
  page131_i32
#ISCELL
  mstr_symbols gnd *
  page131_i33
#CELL
  mstr_discrete cap *
  page131_i34
#CELL
  mstr_discrete cap *
  page131_i35
#ISCELL
  mstr_symbols p1v05_pch_stby *
  page131_i36
#CELL
  mstr_discrete cap *
  page131_i37
#ISCELL
  mstr_symbols gnd *
  page131_i38
#CELL
  dev_discrete cap_a *
  page131_i39
#CELL
  dev_discrete cap_a *
  page131_i4
#CELL
  dev_discrete cap_a *
  page131_i40
#CELL
  dev_discrete cap_a *
  page131_i41
#CELL
  dev_discrete cap_a *
  page131_i42
#CELL
  dev_discrete cap_a *
  page131_i43
#CELL
  dev_discrete cap_a *
  page131_i44
#CELL
  dev_discrete cap_a *
  page131_i45
#ISCELL
  mstr_symbols p1v05_pch_stby *
  page131_i46
#CELL
  dev_discrete cap_a *
  page131_i47
#CELL
  dev_discrete cap_a *
  page131_i48
#ISCELL
  mstr_symbols p1v05_pch_stby *
  page131_i49
#ISCELL
  mstr_symbols p1v05_pch_stby *
  page131_i5
#CELL
  dev_discrete cap_a *
  page131_i50
#ISCELL
  mstr_symbols gnd *
  page131_i51
#CELL
  dev_discrete cap_a *
  page131_i52
#CELL
  dev_discrete cap_a *
  page131_i6
#CELL
  dev_discrete cap_a *
  page131_i7
#CELL
  dev_discrete cap_a *
  page131_i8
#ISCELL
  mstr_symbols gnd *
  page131_i9
